(kicad_pcb
	(version 20260206)
	(generator "pcbnew")
	(generator_version "10.0")
	(general
		(thickness 1.6)
		(legacy_teardrops no)
	)
	(paper "A4")
	(title_block
		(title "pdpb — Lightning_PDPB_BRD.brd")
		(comment 1 "Lightning (Wiwynn / Facebook NVMe JBOF) / footprints 844-850 of 1140")
	)
	(layers
		(0 "F.Cu" signal "TOP")
		(4 "In1.Cu" signal "L2GND")
		(6 "In2.Cu" signal "L3")
		(8 "In3.Cu" signal "L4VCC")
		(10 "In4.Cu" signal "L5VCC")
		(12 "In5.Cu" signal "L6")
		(14 "In6.Cu" signal "L7GND")
		(2 "B.Cu" signal "BOTTOM")
		(9 "F.Adhes" user "F.Adhesive")
		(11 "B.Adhes" user "B.Adhesive")
		(13 "F.Paste" user "Package Geometry/Pastemask Top")
		(15 "B.Paste" user "Package Geometry/Pastemask Bottom")
		(5 "F.SilkS" user "Ref Des/Silkscreen Top")
		(7 "B.SilkS" user "Ref Des/Silkscreen Bottom")
		(1 "F.Mask" user "Board Geometry/Soldermask Top")
		(3 "B.Mask" user "Board Geometry/Soldermask Bottom")
		(17 "Dwgs.User" user "User.Drawings")
		(19 "Cmts.User" user "User.Comments")
		(21 "Eco1.User" user "User.Eco1")
		(23 "Eco2.User" user "User.Eco2")
		(25 "Edge.Cuts" user "Board Geometry/Outline")
		(27 "Margin" user)
		(31 "F.CrtYd" user "Package Geometry/Place Bound Top")
		(29 "B.CrtYd" user "Package Geometry/Place Bound Bottom")
		(35 "F.Fab" user "Ref Des/Assembly Top")
		(33 "B.Fab" user "Ref Des/Assembly Bottom")
	)
	(footprint ""
		(layer "F.Cu")
		(at 215.7984 -495.2238 -90)
		(property "Reference" "SR1092"
			(at 0 0 270)
			(layer "F.SilkS")
			(hide yes)
			(effects
				(font
					(size 1.27 1.27)
				)
			)
		)
		(property "Value" "4K7R2F-GP"
			(at 0.064008 -3.993896 270)
			(unlocked yes)
			(layer "F.Fab")
			(hide yes)
			(effects
				(font
					(size 1.016 1.016)
					(thickness 0.1524)
				)
			)
		)
		(property "Device Type" "R402H16"
			(at 0.064008 -5.517896 270)
			(unlocked yes)
			(layer "F.Fab")
			(hide yes)
			(effects
				(font
					(size 1.016 1.016)
					(thickness 0.1524)
				)
			)
		)
		(duplicate_pad_numbers_are_jumpers no)
		(fp_line
			(start -0.508 -0.9398)
			(end -0.508 0.9398)
			(stroke
				(width 0.1524)
				(type default)
			)
			(layer "F.SilkS")
		)
		(fp_line
			(start 0.508 -0.9398)
			(end -0.508 -0.9398)
			(stroke
				(width 0.1524)
				(type default)
			)
			(layer "F.SilkS")
		)
		(fp_rect
			(start -0.508 0.9398)
			(end 0.508 -0.9398)
			(stroke
				(width 0)
				(type default)
			)
			(fill no)
			(layer "F.CrtYd")
		)
		(fp_rect
			(start -0.508 0.9398)
			(end 0.508 -0.9398)
			(stroke
				(width 0)
				(type default)
			)
			(fill no)
			(layer "F.Fab")
		)
		(pad "1" smd custom
			(at 0 -0.4445 270)
			(size 0.1397 0.1397)
			(layers "F.Cu" "F.Mask" "F.Paste")
			(net "DUALPORTEN#0")
			(options
				(clearance outline)
				(anchor circle)
			)
			(primitives
				(gr_poly
					(pts
						(arc
							(start -0.1778 -0.2794)
							(mid -0.249642 -0.249642)
							(end -0.2794 -0.1778)
						)
						(arc
							(start -0.2794 0.1778)
							(mid -0.249642 0.249642)
							(end -0.1778 0.2794)
						)
						(arc
							(start 0.1778 0.2794)
							(mid 0.249642 0.249642)
							(end 0.2794 0.1778)
						)
						(arc
							(start 0.2794 -0.1778)
							(mid 0.249642 -0.249642)
							(end 0.1778 -0.2794)
						)
					)
					(width 0)
					(fill yes)
				)
			)
		)
		(pad "2" smd custom
			(at 0 0.4445 270)
			(size 0.1397 0.1397)
			(layers "F.Cu" "F.Mask" "F.Paste")
			(net "GND")
			(options
				(clearance outline)
				(anchor circle)
			)
			(primitives
				(gr_poly
					(pts
						(arc
							(start -0.1778 -0.2794)
							(mid -0.249642 -0.249642)
							(end -0.2794 -0.1778)
						)
						(arc
							(start -0.2794 0.1778)
							(mid -0.249642 0.249642)
							(end -0.1778 0.2794)
						)
						(arc
							(start 0.1778 0.2794)
							(mid 0.249642 0.249642)
							(end 0.2794 0.1778)
						)
						(arc
							(start 0.2794 -0.1778)
							(mid 0.249642 -0.249642)
							(end 0.1778 -0.2794)
						)
					)
					(width 0)
					(fill yes)
				)
			)
		)
	)
	(footprint ""
		(layer "F.Cu")
		(at 234.061 -41.771062 -90)
		(property "Reference" "R9407"
			(at 0 0 270)
			(layer "F.SilkS")
			(hide yes)
			(effects
				(font
					(size 1.27 1.27)
				)
			)
		)
		(property "Value" "330R2F-GP"
			(at 0.064008 -3.993896 270)
			(unlocked yes)
			(layer "F.Fab")
			(hide yes)
			(effects
				(font
					(size 1.016 1.016)
					(thickness 0.1524)
				)
			)
		)
		(property "Device Type" "R402H16"
			(at 0.064008 -5.517896 270)
			(unlocked yes)
			(layer "F.Fab")
			(hide yes)
			(effects
				(font
					(size 1.016 1.016)
					(thickness 0.1524)
				)
			)
		)
		(duplicate_pad_numbers_are_jumpers no)
		(fp_line
			(start -0.508 -0.9398)
			(end -0.508 0.9398)
			(stroke
				(width 0.1524)
				(type default)
			)
			(layer "F.SilkS")
		)
		(fp_line
			(start 0.508 -0.9398)
			(end -0.508 -0.9398)
			(stroke
				(width 0.1524)
				(type default)
			)
			(layer "F.SilkS")
		)
		(fp_rect
			(start -0.508 0.9398)
			(end 0.508 -0.9398)
			(stroke
				(width 0)
				(type default)
			)
			(fill no)
			(layer "F.CrtYd")
		)
		(fp_rect
			(start -0.508 0.9398)
			(end 0.508 -0.9398)
			(stroke
				(width 0)
				(type default)
			)
			(fill no)
			(layer "F.Fab")
		)
		(pad "1" smd custom
			(at 0 -0.4445 270)
			(size 0.1397 0.1397)
			(layers "F.Cu" "F.Mask" "F.Paste")
			(net "P3V3")
			(options
				(clearance outline)
				(anchor circle)
			)
			(primitives
				(gr_poly
					(pts
						(arc
							(start -0.1778 -0.2794)
							(mid -0.249642 -0.249642)
							(end -0.2794 -0.1778)
						)
						(arc
							(start -0.2794 0.1778)
							(mid -0.249642 0.249642)
							(end -0.1778 0.2794)
						)
						(arc
							(start 0.1778 0.2794)
							(mid 0.249642 0.249642)
							(end 0.2794 0.1778)
						)
						(arc
							(start 0.2794 -0.1778)
							(mid 0.249642 -0.249642)
							(end 0.1778 -0.2794)
						)
					)
					(width 0)
					(fill yes)
				)
			)
		)
		(pad "2" smd custom
			(at 0 0.4445 270)
			(size 0.1397 0.1397)
			(layers "F.Cu" "F.Mask" "F.Paste")
			(net "DRV_ATTN_4")
			(options
				(clearance outline)
				(anchor circle)
			)
			(primitives
				(gr_poly
					(pts
						(arc
							(start -0.1778 -0.2794)
							(mid -0.249642 -0.249642)
							(end -0.2794 -0.1778)
						)
						(arc
							(start -0.2794 0.1778)
							(mid -0.249642 0.249642)
							(end -0.1778 0.2794)
						)
						(arc
							(start 0.1778 0.2794)
							(mid 0.249642 0.249642)
							(end 0.2794 0.1778)
						)
						(arc
							(start 0.2794 -0.1778)
							(mid 0.249642 -0.249642)
							(end 0.1778 -0.2794)
						)
					)
					(width 0)
					(fill yes)
				)
			)
		)
	)
	(footprint ""
		(layer "F.Cu")
		(at 98.679 -88.138 180)
		(property "Reference" "R9617"
			(at 0 0 180)
			(layer "F.SilkS")
			(hide yes)
			(effects
				(font
					(size 1.27 1.27)
				)
			)
		)
		(property "Value" "10R2F-L-GP"
			(at 0.064008 -3.993896 180)
			(unlocked yes)
			(layer "F.Fab")
			(hide yes)
			(effects
				(font
					(size 1.016 1.016)
					(thickness 0.1524)
				)
			)
		)
		(property "Device Type" "R402H14"
			(at 0.064008 -5.517896 180)
			(unlocked yes)
			(layer "F.Fab")
			(hide yes)
			(effects
				(font
					(size 1.016 1.016)
					(thickness 0.1524)
				)
			)
		)
		(duplicate_pad_numbers_are_jumpers no)
		(fp_line
			(start 0.508 -0.9398)
			(end -0.508 -0.9398)
			(stroke
				(width 0.1524)
				(type default)
			)
			(layer "F.SilkS")
		)
		(fp_line
			(start -0.508 -0.9398)
			(end -0.508 0.9398)
			(stroke
				(width 0.1524)
				(type default)
			)
			(layer "F.SilkS")
		)
		(fp_rect
			(start -0.508 0.9398)
			(end 0.508 -0.9398)
			(stroke
				(width 0)
				(type default)
			)
			(fill no)
			(layer "F.CrtYd")
		)
		(fp_rect
			(start -0.508 0.9398)
			(end 0.508 -0.9398)
			(stroke
				(width 0)
				(type default)
			)
			(fill no)
			(layer "F.Fab")
		)
		(pad "1" smd custom
			(at 0 -0.4445 180)
			(size 0.1397 0.1397)
			(layers "F.Cu" "F.Mask" "F.Paste")
			(net "SSD14_CLK0_OE_N")
			(options
				(clearance outline)
				(anchor circle)
			)
			(primitives
				(gr_poly
					(pts
						(arc
							(start -0.1778 -0.2794)
							(mid -0.249642 -0.249642)
							(end -0.2794 -0.1778)
						)
						(arc
							(start -0.2794 0.1778)
							(mid -0.249642 0.249642)
							(end -0.1778 0.2794)
						)
						(arc
							(start 0.1778 0.2794)
							(mid 0.249642 0.249642)
							(end 0.2794 0.1778)
						)
						(arc
							(start 0.2794 -0.1778)
							(mid 0.249642 -0.249642)
							(end 0.1778 -0.2794)
						)
					)
					(width 0)
					(fill yes)
				)
			)
		)
		(pad "2" smd custom
			(at 0 0.4445 180)
			(size 0.1397 0.1397)
			(layers "F.Cu" "F.Mask" "F.Paste")
			(net "SSD14_CLK0_OE_R_N")
			(options
				(clearance outline)
				(anchor circle)
			)
			(primitives
				(gr_poly
					(pts
						(arc
							(start -0.1778 -0.2794)
							(mid -0.249642 -0.249642)
							(end -0.2794 -0.1778)
						)
						(arc
							(start -0.2794 0.1778)
							(mid -0.249642 0.249642)
							(end -0.1778 0.2794)
						)
						(arc
							(start 0.1778 0.2794)
							(mid 0.249642 0.249642)
							(end 0.2794 0.1778)
						)
						(arc
							(start 0.2794 -0.1778)
							(mid 0.249642 -0.249642)
							(end 0.1778 -0.2794)
						)
					)
					(width 0)
					(fill yes)
				)
			)
		)
	)
	(footprint ""
		(layer "F.Cu")
		(at 70.739 -146.558 90)
		(property "Reference" "SR969"
			(at 0 0 90)
			(layer "F.SilkS")
			(hide yes)
			(effects
				(font
					(size 1.27 1.27)
				)
			)
		)
		(property "Value" "2KR2F-3-GP"
			(at 0.064008 -3.993896 90)
			(unlocked yes)
			(layer "F.Fab")
			(hide yes)
			(effects
				(font
					(size 1.016 1.016)
					(thickness 0.1524)
				)
			)
		)
		(property "Device Type" "R402H16"
			(at 0.064008 -5.517896 90)
			(unlocked yes)
			(layer "F.Fab")
			(hide yes)
			(effects
				(font
					(size 1.016 1.016)
					(thickness 0.1524)
				)
			)
		)
		(duplicate_pad_numbers_are_jumpers no)
		(fp_line
			(start 0.508 -0.9398)
			(end -0.508 -0.9398)
			(stroke
				(width 0.1524)
				(type default)
			)
			(layer "F.SilkS")
		)
		(fp_line
			(start -0.508 -0.9398)
			(end -0.508 0.9398)
			(stroke
				(width 0.1524)
				(type default)
			)
			(layer "F.SilkS")
		)
		(fp_rect
			(start -0.508 0.9398)
			(end 0.508 -0.9398)
			(stroke
				(width 0)
				(type default)
			)
			(fill no)
			(layer "F.CrtYd")
		)
		(fp_rect
			(start -0.508 0.9398)
			(end 0.508 -0.9398)
			(stroke
				(width 0)
				(type default)
			)
			(fill no)
			(layer "F.Fab")
		)
		(pad "1" smd custom
			(at 0 -0.4445 90)
			(size 0.1397 0.1397)
			(layers "F.Cu" "F.Mask" "F.Paste")
			(net "P3V3")
			(options
				(clearance outline)
				(anchor circle)
			)
			(primitives
				(gr_poly
					(pts
						(arc
							(start -0.1778 -0.2794)
							(mid -0.249642 -0.249642)
							(end -0.2794 -0.1778)
						)
						(arc
							(start -0.2794 0.1778)
							(mid -0.249642 0.249642)
							(end -0.1778 0.2794)
						)
						(arc
							(start 0.1778 0.2794)
							(mid 0.249642 0.249642)
							(end 0.2794 0.1778)
						)
						(arc
							(start 0.2794 -0.1778)
							(mid 0.249642 -0.249642)
							(end 0.1778 -0.2794)
						)
					)
					(width 0)
					(fill yes)
				)
			)
		)
		(pad "2" smd custom
			(at 0 0.4445 90)
			(size 0.1397 0.1397)
			(layers "F.Cu" "F.Mask" "F.Paste")
			(net "SCL_DR13")
			(options
				(clearance outline)
				(anchor circle)
			)
			(primitives
				(gr_poly
					(pts
						(arc
							(start -0.1778 -0.2794)
							(mid -0.249642 -0.249642)
							(end -0.2794 -0.1778)
						)
						(arc
							(start -0.2794 0.1778)
							(mid -0.249642 0.249642)
							(end -0.1778 0.2794)
						)
						(arc
							(start 0.1778 0.2794)
							(mid 0.249642 0.249642)
							(end 0.2794 0.1778)
						)
						(arc
							(start 0.2794 -0.1778)
							(mid 0.249642 -0.249642)
							(end 0.1778 -0.2794)
						)
					)
					(width 0)
					(fill yes)
				)
			)
		)
	)
	(footprint ""
		(layer "F.Cu")
		(at 32.131 -287.528 -90)
		(property "Reference" "R401"
			(at 0 0 270)
			(layer "F.SilkS")
			(hide yes)
			(effects
				(font
					(size 1.27 1.27)
				)
			)
		)
		(property "Value" "0R2J-2-GP"
			(at 0.064008 -3.993896 270)
			(unlocked yes)
			(layer "F.Fab")
			(hide yes)
			(effects
				(font
					(size 1.016 1.016)
					(thickness 0.1524)
				)
			)
		)
		(property "Device Type" "R402H16"
			(at 0.064008 -5.517896 270)
			(unlocked yes)
			(layer "F.Fab")
			(hide yes)
			(effects
				(font
					(size 1.016 1.016)
					(thickness 0.1524)
				)
			)
		)
		(duplicate_pad_numbers_are_jumpers no)
		(fp_line
			(start -0.508 -0.9398)
			(end -0.508 0.9398)
			(stroke
				(width 0.1524)
				(type default)
			)
			(layer "F.SilkS")
		)
		(fp_line
			(start 0.508 -0.9398)
			(end -0.508 -0.9398)
			(stroke
				(width 0.1524)
				(type default)
			)
			(layer "F.SilkS")
		)
		(fp_rect
			(start -0.508 0.9398)
			(end 0.508 -0.9398)
			(stroke
				(width 0)
				(type default)
			)
			(fill no)
			(layer "F.CrtYd")
		)
		(fp_rect
			(start -0.508 0.9398)
			(end 0.508 -0.9398)
			(stroke
				(width 0)
				(type default)
			)
			(fill no)
			(layer "F.Fab")
		)
		(pad "1" smd custom
			(at 0 -0.4445 270)
			(size 0.1397 0.1397)
			(layers "F.Cu" "F.Mask" "F.Paste")
			(net "SCL_DR7_R")
			(options
				(clearance outline)
				(anchor circle)
			)
			(primitives
				(gr_poly
					(pts
						(arc
							(start -0.1778 -0.2794)
							(mid -0.249642 -0.249642)
							(end -0.2794 -0.1778)
						)
						(arc
							(start -0.2794 0.1778)
							(mid -0.249642 0.249642)
							(end -0.1778 0.2794)
						)
						(arc
							(start 0.1778 0.2794)
							(mid 0.249642 0.249642)
							(end 0.2794 0.1778)
						)
						(arc
							(start 0.2794 -0.1778)
							(mid 0.249642 -0.249642)
							(end 0.1778 -0.2794)
						)
					)
					(width 0)
					(fill yes)
				)
			)
		)
		(pad "2" smd custom
			(at 0 0.4445 270)
			(size 0.1397 0.1397)
			(layers "F.Cu" "F.Mask" "F.Paste")
			(net "SCL_DR7")
			(options
				(clearance outline)
				(anchor circle)
			)
			(primitives
				(gr_poly
					(pts
						(arc
							(start -0.1778 -0.2794)
							(mid -0.249642 -0.249642)
							(end -0.2794 -0.1778)
						)
						(arc
							(start -0.2794 0.1778)
							(mid -0.249642 0.249642)
							(end -0.1778 0.2794)
						)
						(arc
							(start 0.1778 0.2794)
							(mid 0.249642 0.249642)
							(end 0.2794 0.1778)
						)
						(arc
							(start 0.2794 -0.1778)
							(mid 0.249642 -0.249642)
							(end 0.1778 -0.2794)
						)
					)
					(width 0)
					(fill yes)
				)
			)
		)
	)
	(footprint ""
		(layer "F.Cu")
		(at 29.845 -114.173 90)
		(property "Reference" "R416"
			(at 0 0 90)
			(layer "F.SilkS")
			(hide yes)
			(effects
				(font
					(size 1.27 1.27)
				)
			)
		)
		(property "Value" "0R2J-2-GP"
			(at 0.064008 -3.993896 90)
			(unlocked yes)
			(layer "F.Fab")
			(hide yes)
			(effects
				(font
					(size 1.016 1.016)
					(thickness 0.1524)
				)
			)
		)
		(property "Device Type" "R402H16"
			(at 0.064008 -5.517896 90)
			(unlocked yes)
			(layer "F.Fab")
			(hide yes)
			(effects
				(font
					(size 1.016 1.016)
					(thickness 0.1524)
				)
			)
		)
		(duplicate_pad_numbers_are_jumpers no)
		(fp_line
			(start 0.508 -0.9398)
			(end -0.508 -0.9398)
			(stroke
				(width 0.1524)
				(type default)
			)
			(layer "F.SilkS")
		)
		(fp_line
			(start -0.508 -0.9398)
			(end -0.508 0.9398)
			(stroke
				(width 0.1524)
				(type default)
			)
			(layer "F.SilkS")
		)
		(fp_rect
			(start -0.508 0.9398)
			(end 0.508 -0.9398)
			(stroke
				(width 0)
				(type default)
			)
			(fill no)
			(layer "F.CrtYd")
		)
		(fp_rect
			(start -0.508 0.9398)
			(end 0.508 -0.9398)
			(stroke
				(width 0)
				(type default)
			)
			(fill no)
			(layer "F.Fab")
		)
		(pad "1" smd custom
			(at 0 -0.4445 90)
			(size 0.1397 0.1397)
			(layers "F.Cu" "F.Mask" "F.Paste")
			(net "SDA_DR13_R")
			(options
				(clearance outline)
				(anchor circle)
			)
			(primitives
				(gr_poly
					(pts
						(arc
							(start -0.1778 -0.2794)
							(mid -0.249642 -0.249642)
							(end -0.2794 -0.1778)
						)
						(arc
							(start -0.2794 0.1778)
							(mid -0.249642 0.249642)
							(end -0.1778 0.2794)
						)
						(arc
							(start 0.1778 0.2794)
							(mid 0.249642 0.249642)
							(end 0.2794 0.1778)
						)
						(arc
							(start 0.2794 -0.1778)
							(mid 0.249642 -0.249642)
							(end 0.1778 -0.2794)
						)
					)
					(width 0)
					(fill yes)
				)
			)
		)
		(pad "2" smd custom
			(at 0 0.4445 90)
			(size 0.1397 0.1397)
			(layers "F.Cu" "F.Mask" "F.Paste")
			(net "SDA_DR13")
			(options
				(clearance outline)
				(anchor circle)
			)
			(primitives
				(gr_poly
					(pts
						(arc
							(start -0.1778 -0.2794)
							(mid -0.249642 -0.249642)
							(end -0.2794 -0.1778)
						)
						(arc
							(start -0.2794 0.1778)
							(mid -0.249642 0.249642)
							(end -0.1778 0.2794)
						)
						(arc
							(start 0.1778 0.2794)
							(mid 0.249642 0.249642)
							(end 0.2794 0.1778)
						)
						(arc
							(start 0.2794 -0.1778)
							(mid 0.249642 -0.249642)
							(end 0.1778 -0.2794)
						)
					)
					(width 0)
					(fill yes)
				)
			)
		)
	)
	(footprint ""
		(layer "F.Cu")
		(at 55.753 -241.040158 180)
		(property "Reference" "Q65"
			(at 0 0 180)
			(layer "F.SilkS")
			(hide yes)
			(effects
				(font
					(size 1.27 1.27)
				)
			)
		)
		(property "Value" "2N7002A-7-GP"
			(at 0.127 -8.9662 180)
			(unlocked yes)
			(layer "F.Fab")
			(hide yes)
			(effects
				(font
					(size 1.016 1.016)
					(thickness 0.1524)
				)
			)
		)
		(property "Device Type" "SOT23DGS2D4H48"
			(at 0.127 -10.4902 180)
			(unlocked yes)
			(layer "F.Fab")
			(hide yes)
			(effects
				(font
					(size 1.016 1.016)
					(thickness 0.1524)
				)
			)
		)
		(duplicate_pad_numbers_are_jumpers no)
		(fp_line
			(start 1.651 1.778)
			(end 1.651 -1.778)
			(stroke
				(width 0.1524)
				(type default)
			)
			(layer "F.SilkS")
		)
		(fp_line
			(start 1.651 -1.778)
			(end -1.651 -1.778)
			(stroke
				(width 0.1524)
				(type default)
			)
			(layer "F.SilkS")
		)
		(fp_line
			(start -1.651 1.778)
			(end 1.651 1.778)
			(stroke
				(width 0.1524)
				(type default)
			)
			(layer "F.SilkS")
		)
		(fp_line
			(start -1.651 -1.778)
			(end -1.651 1.778)
			(stroke
				(width 0.1524)
				(type default)
			)
			(layer "F.SilkS")
		)
		(fp_poly
			(pts
				(xy -1.778 1.8796) (xy -1.778 -1.8796) (xy 1.778 -1.8796) (xy 1.778 1.8796)
			)
			(stroke
				(width 0)
				(type default)
			)
			(fill no)
			(layer "F.CrtYd")
		)
		(fp_poly
			(pts
				(xy -1.778 1.8796) (xy -1.778 -1.8796) (xy 1.778 -1.8796) (xy 1.778 1.8796)
			)
			(stroke
				(width 0)
				(type default)
			)
			(fill no)
			(layer "F.Fab")
		)
		(pad "D" smd custom
			(at 0 -0.9525 180)
			(size 0.1905 0.1905)
			(layers "F.Cu" "F.Mask" "F.Paste")
			(net "ATTN_LED_DR7_MOS_N")
			(options
				(clearance outline)
				(anchor circle)
			)
			(primitives
				(gr_poly
					(pts
						(arc
							(start -0.1778 0.5715)
							(mid -0.321484 0.511984)
							(end -0.381 0.3683)
						)
						(arc
							(start -0.381 -0.3683)
							(mid -0.321484 -0.511984)
							(end -0.1778 -0.5715)
						)
						(arc
							(start 0.1778 -0.5715)
							(mid 0.321484 -0.511984)
							(end 0.381 -0.3683)
						)
						(arc
							(start 0.381 0.3683)
							(mid 0.321484 0.511984)
							(end 0.1778 0.5715)
						)
					)
					(width 0)
					(fill yes)
				)
			)
		)
		(pad "G" smd custom
			(at -0.98425 0.9525 180)
			(size 0.1905 0.1905)
			(layers "F.Cu" "F.Mask" "F.Paste")
			(net "SSD7_CLK0_OE_MOS_N")
			(options
				(clearance outline)
				(anchor circle)
			)
			(primitives
				(gr_poly
					(pts
						(arc
							(start -0.1778 0.5715)
							(mid -0.321484 0.511984)
							(end -0.381 0.3683)
						)
						(arc
							(start -0.381 -0.3683)
							(mid -0.321484 -0.511984)
							(end -0.1778 -0.5715)
						)
						(arc
							(start 0.1778 -0.5715)
							(mid 0.321484 -0.511984)
							(end 0.381 -0.3683)
						)
						(arc
							(start 0.381 0.3683)
							(mid 0.321484 0.511984)
							(end 0.1778 0.5715)
						)
					)
					(width 0)
					(fill yes)
				)
			)
		)
		(pad "S" smd custom
			(at 0.98425 0.9525 180)
			(size 0.1905 0.1905)
			(layers "F.Cu" "F.Mask" "F.Paste")
			(net "ATTN_LED_DR7_R")
			(options
				(clearance outline)
				(anchor circle)
			)
			(primitives
				(gr_poly
					(pts
						(arc
							(start -0.1778 0.5715)
							(mid -0.321484 0.511984)
							(end -0.381 0.3683)
						)
						(arc
							(start -0.381 -0.3683)
							(mid -0.321484 -0.511984)
							(end -0.1778 -0.5715)
						)
						(arc
							(start 0.1778 -0.5715)
							(mid 0.321484 -0.511984)
							(end 0.381 -0.3683)
						)
						(arc
							(start 0.381 0.3683)
							(mid 0.321484 0.511984)
							(end 0.1778 0.5715)
						)
					)
					(width 0)
					(fill yes)
				)
			)
		)
	)
)
